(kicad_pcb
	(version 20260206)
	(generator "pcbnew")
	(generator_version "10.0")
	(general
		(thickness 1.6)
		(legacy_teardrops no)
	)
	(paper "A4")
	(title_block
		(title "v1-pdb — T6M_PDB_D_0927_0900.brd")
		(comment 1 "Open CloudServer (Microsoft) / footprints 130-135 of 321")
	)
	(layers
		(0 "F.Cu" signal "TOP")
		(4 "In1.Cu" signal "GND")
		(6 "In2.Cu" signal "IN1")
		(8 "In3.Cu" signal "VCC")
		(10 "In4.Cu" signal "VCC1")
		(12 "In5.Cu" signal "IN2")
		(14 "In6.Cu" signal "GND1")
		(2 "B.Cu" signal "BOTTOM")
		(9 "F.Adhes" user "F.Adhesive")
		(11 "B.Adhes" user "B.Adhesive")
		(13 "F.Paste" user "Package Geometry/Pastemask Top")
		(15 "B.Paste" user "Package Geometry/Pastemask Bottom")
		(5 "F.SilkS" user "Ref Des/Silkscreen Top")
		(7 "B.SilkS" user "Ref Des/Silkscreen Bottom")
		(1 "F.Mask" user "Board Geometry/Soldermask Top")
		(3 "B.Mask" user "Board Geometry/Soldermask Bottom")
		(17 "Dwgs.User" user "User.Drawings")
		(19 "Cmts.User" user "User.Comments")
		(21 "Eco1.User" user "User.Eco1")
		(23 "Eco2.User" user "User.Eco2")
		(25 "Edge.Cuts" user "Board Geometry/Outline")
		(27 "Margin" user)
		(31 "F.CrtYd" user "Package Geometry/Place Bound Top")
		(29 "B.CrtYd" user "Package Geometry/Place Bound Bottom")
		(35 "F.Fab" user "Ref Des/Assembly Top")
		(33 "B.Fab" user "Ref Des/Assembly Bottom")
	)
	(footprint ""
		(layer "F.Cu")
		(at 50.39868 -519.020552 180)
		(property "Reference" "CE24"
			(at 0.751586 5.701792 0)
			(unlocked yes)
			(layer "F.SilkS")
			(effects
				(font
					(size 0.7874 0.5842)
					(thickness 0.1524)
				)
				(justify left)
			)
		)
		(property "Value" ""
			(at 0 0 180)
			(layer "F.Fab")
			(effects
				(font
					(size 1.27 1.27)
				)
			)
		)
		(duplicate_pad_numbers_are_jumpers no)
		(fp_line
			(start 0 -4.2672)
			(end 0 4.2672)
			(stroke
				(width 0.1524)
				(type default)
			)
			(layer "F.SilkS")
		)
		(fp_circle
			(center 0 0)
			(end -4.2672 0)
			(stroke
				(width 0.1524)
				(type default)
			)
			(fill no)
			(layer "F.SilkS")
		)
		(fp_poly
			(pts
				(arc
					(start 0 -4.2672)
					(mid 4.2672 0)
					(end 0 4.2672)
				)
			)
			(stroke
				(width 0)
				(type default)
			)
			(fill yes)
			(layer "F.SilkS")
		)
		(fp_poly
			(pts
				(xy -2.5146 -0.762) (xy -0.9906 -0.762) (xy -0.9906 0.762) (xy -2.5146 0.762)
			)
			(stroke
				(width 0)
				(type default)
			)
			(fill no)
			(layer "B.CrtYd")
		)
		(fp_poly
			(pts
				(arc
					(start 1.7526 0.762)
					(mid 2.291415 -0.538815)
					(end 0.9906 0)
				)
				(arc
					(start 0.9906 0.0254)
					(mid 1.206345 0.546255)
					(end 1.7272 0.762)
				)
			)
			(stroke
				(width 0)
				(type default)
			)
			(fill no)
			(layer "B.CrtYd")
		)
		(fp_poly
			(pts
				(arc
					(start -4.2672 0)
					(mid 4.2672 0)
					(end -4.2672 0)
				)
			)
			(stroke
				(width 0)
				(type default)
			)
			(fill no)
			(layer "F.CrtYd")
		)
		(fp_circle
			(center 0 0)
			(end -4.2672 0)
			(stroke
				(width 0.1)
				(type default)
			)
			(fill no)
			(layer "F.Fab")
		)
		(fp_text user "+"
			(at -5.892292 -1.07823 180)
			(unlocked yes)
			(layer "F.SilkS")
			(effects
				(font
					(size 0.7874 0.5842)
					(thickness 0.1524)
				)
				(justify left)
			)
		)
		(fp_text user "+"
			(at -5.6642 -0.34925 180)
			(unlocked yes)
			(layer "F.Fab")
			(effects
				(font
					(size 1.905 1.4224)
					(thickness 0.000001)
				)
				(justify left)
			)
		)
		(pad "1" thru_hole rect
			(at -1.75006 0 180)
			(size 1.397 1.397)
			(drill 0.9144)
			(layers "*.Cu" "*.Mask")
			(remove_unused_layers no)
			(net "P12V")
			(clearance 0.0127)
			(thermal_gap 0.0127)
			(padstack
				(mode front_inner_back)
				(layer "Inner"
					(shape circle)
					(size 1.397 1.397)
					(clearance 0.0127)
				)
				(layer "B.Cu"
					(shape rect)
					(size 1.397 1.397)
					(clearance 0.0127)
				)
			)
		)
		(pad "2" thru_hole circle
			(at 1.75006 0 180)
			(size 1.397 1.397)
			(drill 0.9144)
			(layers "*.Cu" "*.Mask")
			(remove_unused_layers no)
			(net "GND")
			(clearance 0.0127)
			(thermal_gap 0.0127)
		)
	)
	(footprint ""
		(layer "F.Cu")
		(at 69.863208 -354.308664 90)
		(property "Reference" "C62"
			(at -3.926078 0.348742 90)
			(unlocked yes)
			(layer "F.SilkS")
			(effects
				(font
					(size 0.7874 0.5842)
					(thickness 0.1524)
				)
				(justify left)
			)
		)
		(property "Value" ""
			(at 0 0 90)
			(layer "F.Fab")
			(effects
				(font
					(size 1.27 1.27)
				)
			)
		)
		(duplicate_pad_numbers_are_jumpers no)
		(fp_line
			(start 0.7874 -0.4064)
			(end 0.7874 0.4064)
			(stroke
				(width 0.1524)
				(type default)
			)
			(layer "F.SilkS")
		)
		(fp_line
			(start -0.7874 -0.4064)
			(end 0.7874 -0.4064)
			(stroke
				(width 0.1524)
				(type default)
			)
			(layer "F.SilkS")
		)
		(fp_line
			(start 0 0.381)
			(end 0 -0.381)
			(stroke
				(width 0.1524)
				(type default)
			)
			(layer "F.SilkS")
		)
		(fp_line
			(start 0.7874 0.4064)
			(end -0.7874 0.4064)
			(stroke
				(width 0.1524)
				(type default)
			)
			(layer "F.SilkS")
		)
		(fp_line
			(start -0.7874 0.4064)
			(end -0.7874 -0.4064)
			(stroke
				(width 0.1524)
				(type default)
			)
			(layer "F.SilkS")
		)
		(fp_poly
			(pts
				(xy -0.5334 0.254) (xy -0.635 0.254) (xy -0.635 0.2286) (xy -0.635 -0.254) (xy -0.5334 -0.254) (xy -0.5334 -0.2794)
				(xy 0.5334 -0.2794) (xy 0.5334 -0.254) (xy 0.635 -0.254) (xy 0.635 0.254) (xy 0.5334 0.254) (xy 0.5334 0.2794)
				(xy -0.508 0.2794) (xy -0.5334 0.2794)
			)
			(stroke
				(width 0)
				(type default)
			)
			(fill no)
			(layer "F.CrtYd")
		)
		(pad "1" smd rect
			(at 0.40005 0 90)
			(size 0.4572 0.508)
			(layers "F.Cu" "F.Mask" "F.Paste")
			(net "P12V")
		)
		(pad "2" smd rect
			(at -0.40005 0 90)
			(size 0.4572 0.508)
			(layers "F.Cu" "F.Mask" "F.Paste")
			(net "GND")
		)
	)
	(footprint ""
		(layer "F.Cu")
		(at 69.133974 -220.425772 90)
		(property "Reference" "C42"
			(at -3.891534 -0.291846 90)
			(unlocked yes)
			(layer "F.SilkS")
			(effects
				(font
					(size 0.7874 0.5842)
					(thickness 0.1524)
				)
				(justify left)
			)
		)
		(property "Value" ""
			(at 0 0 90)
			(layer "F.Fab")
			(effects
				(font
					(size 1.27 1.27)
				)
			)
		)
		(duplicate_pad_numbers_are_jumpers no)
		(fp_line
			(start 0.7874 -0.4064)
			(end 0.7874 0.4064)
			(stroke
				(width 0.1524)
				(type default)
			)
			(layer "F.SilkS")
		)
		(fp_line
			(start -0.7874 -0.4064)
			(end 0.7874 -0.4064)
			(stroke
				(width 0.1524)
				(type default)
			)
			(layer "F.SilkS")
		)
		(fp_line
			(start 0 0.381)
			(end 0 -0.381)
			(stroke
				(width 0.1524)
				(type default)
			)
			(layer "F.SilkS")
		)
		(fp_line
			(start 0.7874 0.4064)
			(end -0.7874 0.4064)
			(stroke
				(width 0.1524)
				(type default)
			)
			(layer "F.SilkS")
		)
		(fp_line
			(start -0.7874 0.4064)
			(end -0.7874 -0.4064)
			(stroke
				(width 0.1524)
				(type default)
			)
			(layer "F.SilkS")
		)
		(fp_poly
			(pts
				(xy -0.5334 0.254) (xy -0.635 0.254) (xy -0.635 0.2286) (xy -0.635 -0.254) (xy -0.5334 -0.254) (xy -0.5334 -0.2794)
				(xy 0.5334 -0.2794) (xy 0.5334 -0.254) (xy 0.635 -0.254) (xy 0.635 0.254) (xy 0.5334 0.254) (xy 0.5334 0.2794)
				(xy -0.508 0.2794) (xy -0.5334 0.2794)
			)
			(stroke
				(width 0)
				(type default)
			)
			(fill no)
			(layer "F.CrtYd")
		)
		(pad "1" smd rect
			(at 0.40005 0 90)
			(size 0.4572 0.508)
			(layers "F.Cu" "F.Mask" "F.Paste")
			(net "P12V")
		)
		(pad "2" smd rect
			(at -0.40005 0 90)
			(size 0.4572 0.508)
			(layers "F.Cu" "F.Mask" "F.Paste")
			(net "GND")
		)
	)
	(footprint ""
		(layer "F.Cu")
		(at 72.932798 -473.59951 180)
		(property "Reference" "R131"
			(at 0.900176 1.046988 0)
			(unlocked yes)
			(layer "F.SilkS")
			(effects
				(font
					(size 0.7874 0.5842)
					(thickness 0.1524)
				)
				(justify left)
			)
		)
		(property "Value" ""
			(at 0 0 180)
			(layer "F.Fab")
			(effects
				(font
					(size 1.27 1.27)
				)
			)
		)
		(duplicate_pad_numbers_are_jumpers no)
		(fp_line
			(start 0.7874 0.4064)
			(end -0.7874 0.4064)
			(stroke
				(width 0.1524)
				(type default)
			)
			(layer "F.SilkS")
		)
		(fp_line
			(start 0.7874 -0.4064)
			(end 0.7874 0.4064)
			(stroke
				(width 0.1524)
				(type default)
			)
			(layer "F.SilkS")
		)
		(fp_line
			(start -0.7874 0.4064)
			(end -0.7874 -0.4064)
			(stroke
				(width 0.1524)
				(type default)
			)
			(layer "F.SilkS")
		)
		(fp_line
			(start -0.7874 -0.4064)
			(end 0.7874 -0.4064)
			(stroke
				(width 0.1524)
				(type default)
			)
			(layer "F.SilkS")
		)
		(fp_poly
			(pts
				(xy -0.508 0.2794) (xy -0.508 0.2286) (xy -0.635 0.2286) (xy -0.635 -0.254) (xy -0.5334 -0.254)
				(xy -0.5334 -0.2794) (xy 0.5334 -0.2794) (xy 0.5334 -0.254) (xy 0.635 -0.254) (xy 0.635 0.254) (xy 0.5334 0.254)
				(xy 0.5334 0.2794)
			)
			(stroke
				(width 0)
				(type default)
			)
			(fill no)
			(layer "F.CrtYd")
		)
		(pad "1" smd rect
			(at 0.40005 0 180)
			(size 0.4572 0.508)
			(layers "F.Cu" "F.Mask" "F.Paste")
			(net "PSU6_REMOTE_R2_P")
		)
		(pad "2" smd rect
			(at -0.40005 0 180)
			(size 0.4572 0.508)
			(layers "F.Cu" "F.Mask" "F.Paste")
			(net "P12V")
		)
	)
	(footprint ""
		(layer "F.Cu")
		(at 75.91298 -397.262604 90)
		(property "Reference" "C67"
			(at -1.66243 -4.655312 90)
			(unlocked yes)
			(layer "F.SilkS")
			(effects
				(font
					(size 0.7874 0.5842)
					(thickness 0.1524)
				)
				(justify left)
			)
		)
		(property "Value" ""
			(at 0 0 90)
			(layer "F.Fab")
			(effects
				(font
					(size 1.27 1.27)
				)
			)
		)
		(duplicate_pad_numbers_are_jumpers no)
		(fp_line
			(start 0.7874 -0.4064)
			(end 0.7874 0.4064)
			(stroke
				(width 0.1524)
				(type default)
			)
			(layer "F.SilkS")
		)
		(fp_line
			(start -0.7874 -0.4064)
			(end 0.7874 -0.4064)
			(stroke
				(width 0.1524)
				(type default)
			)
			(layer "F.SilkS")
		)
		(fp_line
			(start 0 0.381)
			(end 0 -0.381)
			(stroke
				(width 0.1524)
				(type default)
			)
			(layer "F.SilkS")
		)
		(fp_line
			(start 0.7874 0.4064)
			(end -0.7874 0.4064)
			(stroke
				(width 0.1524)
				(type default)
			)
			(layer "F.SilkS")
		)
		(fp_line
			(start -0.7874 0.4064)
			(end -0.7874 -0.4064)
			(stroke
				(width 0.1524)
				(type default)
			)
			(layer "F.SilkS")
		)
		(fp_poly
			(pts
				(xy -0.5334 0.254) (xy -0.635 0.254) (xy -0.635 0.2286) (xy -0.635 -0.254) (xy -0.5334 -0.254) (xy -0.5334 -0.2794)
				(xy 0.5334 -0.2794) (xy 0.5334 -0.254) (xy 0.635 -0.254) (xy 0.635 0.254) (xy 0.5334 0.254) (xy 0.5334 0.2794)
				(xy -0.508 0.2794) (xy -0.5334 0.2794)
			)
			(stroke
				(width 0)
				(type default)
			)
			(fill no)
			(layer "F.CrtYd")
		)
		(pad "1" smd rect
			(at 0.40005 0 90)
			(size 0.4572 0.508)
			(layers "F.Cu" "F.Mask" "F.Paste")
			(net "P12V")
		)
		(pad "2" smd rect
			(at -0.40005 0 90)
			(size 0.4572 0.508)
			(layers "F.Cu" "F.Mask" "F.Paste")
			(net "GND")
		)
	)
	(footprint ""
		(layer "F.Cu")
		(at 14.309598 -223.205294)
		(property "Reference" ""
			(at 0 0 0)
			(layer "F.SilkS")
			(hide yes)
			(effects
				(font
					(size 1.27 1.27)
				)
			)
		)
		(property "Value" ""
			(at 0 0 0)
			(layer "F.Fab")
			(effects
				(font
					(size 1.27 1.27)
				)
			)
		)
		(duplicate_pad_numbers_are_jumpers no)
		(fp_poly
			(pts
				(arc
					(start 1.4986 0)
					(mid -1.4986 0)
					(end 1.4986 0)
				)
			)
			(stroke
				(width 0)
				(type default)
			)
			(fill no)
			(layer "F.CrtYd")
		)
		(pad "1" smd circle
			(at 0 0)
			(size 0.9906 0.9906)
			(layers "F.Cu" "F.Mask" "F.Paste")
			(net "Net_145")
		)
		(zone
			(layer "F.Cu")
			(hatch none 0.5)
			(connect_pads
				(clearance 0)
			)
			(min_thickness 0.25)
			(keepout
				(tracks not_allowed)
				(vias allowed)
				(pads allowed)
				(copperpour not_allowed)
				(footprints allowed)
			)
			(placement
				(enabled no)
				(sheetname "")
			)
			(fill
				(thermal_gap 0.5)
				(thermal_bridge_width 0.5)
				(island_removal_mode 0)
			)
			(polygon
				(pts
					(arc
						(start 15.935198 -223.205294)
						(mid 12.683998 -223.205294)
						(end 15.935198 -223.205294)
					)
				)
			)
		)
	)
)
